# SCM (Grand Teton) — schematic netlist excerpt (pin names and nets, part order shuffled) for the footprints in the layout excerpt that follows; sources: Cadence DE-HDL packaged netlist, KiCad conversion of 12092022_DA0F0TMDCD0_F0T_Management_Board_D_brd_V3_OCP.brd

C165  Q_CAP  1UF 25V 10% X6S  pkg C0402  page 41 : A = VCCIO2 ; B = GND
C43  Q_CAP  1UF 25V 10% X6S  pkg C0402  page 15 : A = PVCCIO_PECI_BMC ; B = GND

(kicad_pcb
	(version 20260206)
	(generator "pcbnew")
	(generator_version "10.0")
	(general
		(thickness 1.6)
		(legacy_teardrops no)
	)
	(paper "A4")
	(title_block
		(title "12092022_DA0F0TMDCD0_F0T_Management_Board_D_brd_V3_OCP.brd")
		(comment 1 "Grand Teton / footprints 1363-1364 of 1440")
	)
	(layers
		(0 "F.Cu" signal "TOP")
		(4 "In1.Cu" signal "GND")
		(6 "In2.Cu" signal "IN1")
		(8 "In3.Cu" signal "GND1")
		(10 "In4.Cu" signal "IN2")
		(12 "In5.Cu" signal "VCC")
		(14 "In6.Cu" signal "VCC1")
		(16 "In7.Cu" signal "IN3")
		(18 "In8.Cu" signal "GND2")
		(20 "In9.Cu" signal "IN4")
		(22 "In10.Cu" signal "GND3")
		(2 "B.Cu" signal "BOTTOM")
		(9 "F.Adhes" user "F.Adhesive")
		(11 "B.Adhes" user "B.Adhesive")
		(13 "F.Paste" user "Package Geometry/Pastemask Top")
		(15 "B.Paste" user "Package Geometry/Pastemask Bottom")
		(5 "F.SilkS" user "Ref Des/Silkscreen Top")
		(7 "B.SilkS" user "Ref Des/Silkscreen Bottom")
		(1 "F.Mask" user "Board Geometry/Soldermask Top")
		(3 "B.Mask" user "Board Geometry/Soldermask Bottom")
		(17 "Dwgs.User" user "User.Drawings")
		(19 "Cmts.User" user "User.Comments")
		(21 "Eco1.User" user "User.Eco1")
		(23 "Eco2.User" user "User.Eco2")
		(25 "Edge.Cuts" user "Board Geometry/Outline")
		(27 "Margin" user)
		(31 "F.CrtYd" user "Package Geometry/Place Bound Top")
		(29 "B.CrtYd" user "Package Geometry/Place Bound Bottom")
		(35 "F.Fab" user "Ref Des/Assembly Top")
		(33 "B.Fab" user "Ref Des/Assembly Bottom")
	)
	(footprint ""
		(layer "B.Cu")
		(at 40.427656 -56.436006 -90)
		(property "Reference" "C43"
			(at 0 0 90)
			(layer "B.SilkS")
			(hide yes)
			(effects
				(font
					(size 1.27 1.27)
				)
				(justify mirror)
			)
		)
		(property "Value" ""
			(at 0 0 90)
			(layer "B.Fab")
			(effects
				(font
					(size 1.27 1.27)
				)
				(justify mirror)
			)
		)
		(duplicate_pad_numbers_are_jumpers no)
		(fp_line
			(start -0.7874 0.4064)
			(end 0.7874 0.4064)
			(stroke
				(width 0.1524)
				(type default)
			)
			(layer "B.SilkS")
		)
		(fp_line
			(start 0.7874 0.4064)
			(end 0.7874 -0.4064)
			(stroke
				(width 0.1524)
				(type default)
			)
			(layer "B.SilkS")
		)
		(fp_line
			(start -0.7874 -0.4064)
			(end -0.7874 0.4064)
			(stroke
				(width 0.1524)
				(type default)
			)
			(layer "B.SilkS")
		)
		(fp_line
			(start 0.7874 -0.4064)
			(end -0.7874 -0.4064)
			(stroke
				(width 0.1524)
				(type default)
			)
			(layer "B.SilkS")
		)
		(fp_line
			(start -0.67945 0.3048)
			(end -0.120396 0.3048)
			(stroke
				(width 0.1)
				(type default)
			)
			(layer "B.Fab")
		)
		(fp_line
			(start -0.120396 0.3048)
			(end -0.120396 0.2794)
			(stroke
				(width 0.1)
				(type default)
			)
			(layer "B.Fab")
		)
		(fp_line
			(start 0.12065 0.3048)
			(end 0.67945 0.3048)
			(stroke
				(width 0.1)
				(type default)
			)
			(layer "B.Fab")
		)
		(fp_line
			(start 0.67945 0.3048)
			(end 0.67945 -0.305054)
			(stroke
				(width 0.1)
				(type default)
			)
			(layer "B.Fab")
		)
		(fp_line
			(start -0.120396 0.2794)
			(end 0.12065 0.2794)
			(stroke
				(width 0.1)
				(type default)
			)
			(layer "B.Fab")
		)
		(fp_line
			(start 0.12065 0.2794)
			(end 0.12065 0.3048)
			(stroke
				(width 0.1)
				(type default)
			)
			(layer "B.Fab")
		)
		(fp_line
			(start -0.12065 -0.2794)
			(end -0.12065 -0.3048)
			(stroke
				(width 0.1)
				(type default)
			)
			(layer "B.Fab")
		)
		(fp_line
			(start 0.12065 -0.2794)
			(end -0.12065 -0.2794)
			(stroke
				(width 0.1)
				(type default)
			)
			(layer "B.Fab")
		)
		(fp_line
			(start -0.67945 -0.3048)
			(end -0.67945 0.3048)
			(stroke
				(width 0.1)
				(type default)
			)
			(layer "B.Fab")
		)
		(fp_line
			(start -0.12065 -0.3048)
			(end -0.67945 -0.3048)
			(stroke
				(width 0.1)
				(type default)
			)
			(layer "B.Fab")
		)
		(fp_line
			(start 0.12065 -0.305054)
			(end 0.12065 -0.2794)
			(stroke
				(width 0.1)
				(type default)
			)
			(layer "B.Fab")
		)
		(fp_line
			(start 0.67945 -0.305054)
			(end 0.12065 -0.305054)
			(stroke
				(width 0.1)
				(type default)
			)
			(layer "B.Fab")
		)
		(pad "1" smd circle
			(at 0.40005 0 90)
			(size 0 0)
			(layers "B.Cu" "B.Mask" "B.Paste")
			(net "PVCCIO_PECI_BMC")
		)
		(pad "2" smd circle
			(at -0.40005 0 90)
			(size 0 0)
			(layers "B.Cu" "B.Mask" "B.Paste")
			(net "GND")
		)
	)
	(footprint ""
		(layer "B.Cu")
		(at 18.664428 -96.786954 90)
		(property "Reference" "C165"
			(at 0 0 90)
			(layer "B.SilkS")
			(hide yes)
			(effects
				(font
					(size 1.27 1.27)
				)
				(justify mirror)
			)
		)
		(property "Value" ""
			(at 0 0 90)
			(layer "B.Fab")
			(effects
				(font
					(size 1.27 1.27)
				)
				(justify mirror)
			)
		)
		(duplicate_pad_numbers_are_jumpers no)
		(fp_line
			(start 0.69215 -0.2921)
			(end -0.69215 -0.2921)
			(stroke
				(width 0.1524)
				(type default)
			)
			(layer "B.SilkS")
		)
		(fp_line
			(start -0.69215 -0.2921)
			(end -0.69215 0.2921)
			(stroke
				(width 0.1524)
				(type default)
			)
			(layer "B.SilkS")
		)
		(fp_line
			(start 0.69215 0.2921)
			(end 0.69215 -0.2921)
			(stroke
				(width 0.1524)
				(type default)
			)
			(layer "B.SilkS")
		)
		(fp_line
			(start -0.69215 0.2921)
			(end 0.69215 0.2921)
			(stroke
				(width 0.1524)
				(type default)
			)
			(layer "B.SilkS")
		)
		(fp_line
			(start 0.51435 -0.2794)
			(end -0.51435 -0.2794)
			(stroke
				(width 0.1)
				(type default)
			)
			(layer "B.Fab")
		)
		(fp_line
			(start -0.51435 -0.2794)
			(end -0.51435 0.2794)
			(stroke
				(width 0.1)
				(type default)
			)
			(layer "B.Fab")
		)
		(fp_line
			(start 0.51435 0.2794)
			(end 0.51435 -0.2794)
			(stroke
				(width 0.1)
				(type default)
			)
			(layer "B.Fab")
		)
		(fp_line
			(start -0.51435 0.2794)
			(end 0.51435 0.2794)
			(stroke
				(width 0.1)
				(type default)
			)
			(layer "B.Fab")
		)
		(pad "1" smd circle
			(at 0.40005 0 270)
			(size 0 0)
			(layers "B.Cu" "B.Mask" "B.Paste")
			(net "VCCIO2")
		)
		(pad "2" smd circle
			(at -0.40005 0 270)
			(size 0 0)
			(layers "B.Cu" "B.Mask" "B.Paste")
			(net "GND")
		)
		(zone
			(layer "B.Cu")
			(hatch none 0.5)
			(connect_pads
				(clearance 0)
			)
			(min_thickness 0.25)
			(keepout
				(tracks not_allowed)
				(vias allowed)
				(pads allowed)
				(copperpour not_allowed)
				(footprints allowed)
			)
			(placement
				(enabled no)
				(sheetname "")
			)
			(fill
				(thermal_gap 0.5)
				(thermal_bridge_width 0.5)
				(island_removal_mode 0)
			)
			(polygon
				(pts
					(xy 18.752058 -96.977454) (xy 18.810224 -96.886014) (xy 18.810224 -96.686624) (xy 18.752058 -96.596454)
					(xy 18.576798 -96.596454) (xy 18.518378 -96.686624) (xy 18.518378 -96.886014) (xy 18.576544 -96.977454)
				)
			)
		)
	)
)
